(kicad_pcb
	(version 20260206)
	(generator "pcbnew")
	(generator_version "10.0")
	(general
		(thickness 1.6)
		(legacy_teardrops no)
	)
	(paper "A4")
	(title_block
		(title "01162023_DA0F0TEBIF0_F0T_Expander_BD_F_brd_V02_OCP.brd")
		(comment 1 "Grand Teton / footprints 4827-4832 of 9728")
	)
	(layers
		(0 "F.Cu" signal "TOP")
		(4 "In1.Cu" signal "GND")
		(6 "In2.Cu" signal "VCC")
		(8 "In3.Cu" signal "VCC1")
		(10 "In4.Cu" signal "GND1")
		(12 "In5.Cu" signal "IN1")
		(14 "In6.Cu" signal "GND2")
		(16 "In7.Cu" signal "IN2")
		(18 "In8.Cu" signal "GND3")
		(20 "In9.Cu" signal "IN3")
		(22 "In10.Cu" signal "GND4")
		(24 "In11.Cu" signal "IN4")
		(26 "In12.Cu" signal "GND5")
		(28 "In13.Cu" signal "IN5")
		(30 "In14.Cu" signal "GND6")
		(32 "In15.Cu" signal "IN6")
		(34 "In16.Cu" signal "GND7")
		(2 "B.Cu" signal "BOTTOM")
		(9 "F.Adhes" user "F.Adhesive")
		(11 "B.Adhes" user "B.Adhesive")
		(13 "F.Paste" user "Package Geometry/Pastemask Top")
		(15 "B.Paste" user "Package Geometry/Pastemask Bottom")
		(5 "F.SilkS" user "Ref Des/Silkscreen Top")
		(7 "B.SilkS" user "Ref Des/Silkscreen Bottom")
		(1 "F.Mask" user "Board Geometry/Soldermask Top")
		(3 "B.Mask" user "Board Geometry/Soldermask Bottom")
		(17 "Dwgs.User" user "User.Drawings")
		(19 "Cmts.User" user "User.Comments")
		(21 "Eco1.User" user "User.Eco1")
		(23 "Eco2.User" user "User.Eco2")
		(25 "Edge.Cuts" user "Board Geometry/Outline")
		(27 "Margin" user)
		(31 "F.CrtYd" user "Package Geometry/Place Bound Top")
		(29 "B.CrtYd" user "Package Geometry/Place Bound Bottom")
		(35 "F.Fab" user "Ref Des/Assembly Top")
		(33 "B.Fab" user "Ref Des/Assembly Bottom")
	)
	(footprint ""
		(layer "F.Cu")
		(at 431.01514 -59.546236 90)
		(property "Reference" "C2899"
			(at 0 0 90)
			(layer "F.SilkS")
			(hide yes)
			(effects
				(font
					(size 1.27 1.27)
				)
			)
		)
		(property "Value" ""
			(at 0 0 90)
			(layer "F.Fab")
			(effects
				(font
					(size 1.27 1.27)
				)
			)
		)
		(duplicate_pad_numbers_are_jumpers no)
		(fp_line
			(start 0.7874 -0.4064)
			(end 0.7874 0.4064)
			(stroke
				(width 0.1524)
				(type default)
			)
			(layer "F.SilkS")
		)
		(fp_line
			(start -0.7874 -0.4064)
			(end 0.7874 -0.4064)
			(stroke
				(width 0.1524)
				(type default)
			)
			(layer "F.SilkS")
		)
		(fp_line
			(start 0.7874 0.4064)
			(end -0.7874 0.4064)
			(stroke
				(width 0.1524)
				(type default)
			)
			(layer "F.SilkS")
		)
		(fp_line
			(start -0.7874 0.4064)
			(end -0.7874 -0.4064)
			(stroke
				(width 0.1524)
				(type default)
			)
			(layer "F.SilkS")
		)
		(fp_line
			(start -0.12065 -0.305054)
			(end -0.12065 -0.2794)
			(stroke
				(width 0.1)
				(type default)
			)
			(layer "F.Fab")
		)
		(fp_line
			(start -0.67945 -0.305054)
			(end -0.12065 -0.305054)
			(stroke
				(width 0.1)
				(type default)
			)
			(layer "F.Fab")
		)
		(fp_line
			(start 0.67945 -0.3048)
			(end 0.67945 0.3048)
			(stroke
				(width 0.1)
				(type default)
			)
			(layer "F.Fab")
		)
		(fp_line
			(start 0.12065 -0.3048)
			(end 0.67945 -0.3048)
			(stroke
				(width 0.1)
				(type default)
			)
			(layer "F.Fab")
		)
		(fp_line
			(start 0.12065 -0.2794)
			(end 0.12065 -0.3048)
			(stroke
				(width 0.1)
				(type default)
			)
			(layer "F.Fab")
		)
		(fp_line
			(start -0.12065 -0.2794)
			(end 0.12065 -0.2794)
			(stroke
				(width 0.1)
				(type default)
			)
			(layer "F.Fab")
		)
		(fp_line
			(start 0.120396 0.2794)
			(end -0.12065 0.2794)
			(stroke
				(width 0.1)
				(type default)
			)
			(layer "F.Fab")
		)
		(fp_line
			(start -0.12065 0.2794)
			(end -0.12065 0.3048)
			(stroke
				(width 0.1)
				(type default)
			)
			(layer "F.Fab")
		)
		(fp_line
			(start 0.67945 0.3048)
			(end 0.120396 0.3048)
			(stroke
				(width 0.1)
				(type default)
			)
			(layer "F.Fab")
		)
		(fp_line
			(start 0.120396 0.3048)
			(end 0.120396 0.2794)
			(stroke
				(width 0.1)
				(type default)
			)
			(layer "F.Fab")
		)
		(fp_line
			(start -0.12065 0.3048)
			(end -0.67945 0.3048)
			(stroke
				(width 0.1)
				(type default)
			)
			(layer "F.Fab")
		)
		(fp_line
			(start -0.67945 0.3048)
			(end -0.67945 -0.305054)
			(stroke
				(width 0.1)
				(type default)
			)
			(layer "F.Fab")
		)
		(pad "1" smd circle
			(at -0.40005 0 90)
			(size 0 0)
			(layers "F.Cu" "F.Mask" "F.Paste")
			(net "SSD15_AUX_P3V3_EN_R")
		)
		(pad "2" smd circle
			(at 0.40005 0 90)
			(size 0 0)
			(layers "F.Cu" "F.Mask" "F.Paste")
			(net "GND")
		)
	)
	(footprint ""
		(layer "F.Cu")
		(at 10.716768 -162.003994 90)
		(property "Reference" "PC612"
			(at 0 0 90)
			(layer "F.SilkS")
			(hide yes)
			(effects
				(font
					(size 1.27 1.27)
				)
			)
		)
		(property "Value" ""
			(at 0 0 90)
			(layer "F.Fab")
			(effects
				(font
					(size 1.27 1.27)
				)
			)
		)
		(duplicate_pad_numbers_are_jumpers no)
		(fp_line
			(start 0.7874 -0.4064)
			(end 0.7874 0.4064)
			(stroke
				(width 0.1524)
				(type default)
			)
			(layer "F.SilkS")
		)
		(fp_line
			(start -0.7874 -0.4064)
			(end 0.7874 -0.4064)
			(stroke
				(width 0.1524)
				(type default)
			)
			(layer "F.SilkS")
		)
		(fp_line
			(start 0.7874 0.4064)
			(end -0.7874 0.4064)
			(stroke
				(width 0.1524)
				(type default)
			)
			(layer "F.SilkS")
		)
		(fp_line
			(start -0.7874 0.4064)
			(end -0.7874 -0.4064)
			(stroke
				(width 0.1524)
				(type default)
			)
			(layer "F.SilkS")
		)
		(fp_line
			(start -0.12065 -0.305054)
			(end -0.12065 -0.2794)
			(stroke
				(width 0.1)
				(type default)
			)
			(layer "F.Fab")
		)
		(fp_line
			(start -0.67945 -0.305054)
			(end -0.12065 -0.305054)
			(stroke
				(width 0.1)
				(type default)
			)
			(layer "F.Fab")
		)
		(fp_line
			(start 0.67945 -0.3048)
			(end 0.67945 0.3048)
			(stroke
				(width 0.1)
				(type default)
			)
			(layer "F.Fab")
		)
		(fp_line
			(start 0.12065 -0.3048)
			(end 0.67945 -0.3048)
			(stroke
				(width 0.1)
				(type default)
			)
			(layer "F.Fab")
		)
		(fp_line
			(start 0.12065 -0.2794)
			(end 0.12065 -0.3048)
			(stroke
				(width 0.1)
				(type default)
			)
			(layer "F.Fab")
		)
		(fp_line
			(start -0.12065 -0.2794)
			(end 0.12065 -0.2794)
			(stroke
				(width 0.1)
				(type default)
			)
			(layer "F.Fab")
		)
		(fp_line
			(start 0.120396 0.2794)
			(end -0.12065 0.2794)
			(stroke
				(width 0.1)
				(type default)
			)
			(layer "F.Fab")
		)
		(fp_line
			(start -0.12065 0.2794)
			(end -0.12065 0.3048)
			(stroke
				(width 0.1)
				(type default)
			)
			(layer "F.Fab")
		)
		(fp_line
			(start 0.67945 0.3048)
			(end 0.120396 0.3048)
			(stroke
				(width 0.1)
				(type default)
			)
			(layer "F.Fab")
		)
		(fp_line
			(start 0.120396 0.3048)
			(end 0.120396 0.2794)
			(stroke
				(width 0.1)
				(type default)
			)
			(layer "F.Fab")
		)
		(fp_line
			(start -0.12065 0.3048)
			(end -0.67945 0.3048)
			(stroke
				(width 0.1)
				(type default)
			)
			(layer "F.Fab")
		)
		(fp_line
			(start -0.67945 0.3048)
			(end -0.67945 -0.305054)
			(stroke
				(width 0.1)
				(type default)
			)
			(layer "F.Fab")
		)
		(pad "1" smd circle
			(at -0.40005 0 90)
			(size 0 0)
			(layers "F.Cu" "F.Mask" "F.Paste")
			(net "P12V_NIC0_CO_SS")
		)
		(pad "2" smd circle
			(at 0.40005 0 90)
			(size 0 0)
			(layers "F.Cu" "F.Mask" "F.Paste")
			(net "GND")
		)
	)
	(footprint ""
		(layer "F.Cu")
		(at 118.975378 -64.102234 180)
		(property "Reference" "PR7067"
			(at 0 0 180)
			(layer "F.SilkS")
			(hide yes)
			(effects
				(font
					(size 1.27 1.27)
				)
			)
		)
		(property "Value" ""
			(at 0 0 180)
			(layer "F.Fab")
			(effects
				(font
					(size 1.27 1.27)
				)
			)
		)
		(duplicate_pad_numbers_are_jumpers no)
		(fp_line
			(start 0.7874 0.4064)
			(end -0.7874 0.4064)
			(stroke
				(width 0.1524)
				(type default)
			)
			(layer "F.SilkS")
		)
		(fp_line
			(start 0.7874 -0.4064)
			(end 0.7874 0.4064)
			(stroke
				(width 0.1524)
				(type default)
			)
			(layer "F.SilkS")
		)
		(fp_line
			(start -0.7874 0.4064)
			(end -0.7874 -0.4064)
			(stroke
				(width 0.1524)
				(type default)
			)
			(layer "F.SilkS")
		)
		(fp_line
			(start -0.7874 -0.4064)
			(end 0.7874 -0.4064)
			(stroke
				(width 0.1524)
				(type default)
			)
			(layer "F.SilkS")
		)
		(fp_line
			(start 0.67945 0.3048)
			(end 0.120396 0.3048)
			(stroke
				(width 0.1)
				(type default)
			)
			(layer "F.Fab")
		)
		(fp_line
			(start 0.67945 -0.3048)
			(end 0.67945 0.3048)
			(stroke
				(width 0.1)
				(type default)
			)
			(layer "F.Fab")
		)
		(fp_line
			(start 0.12065 -0.2794)
			(end 0.12065 -0.3048)
			(stroke
				(width 0.1)
				(type default)
			)
			(layer "F.Fab")
		)
		(fp_line
			(start 0.12065 -0.3048)
			(end 0.67945 -0.3048)
			(stroke
				(width 0.1)
				(type default)
			)
			(layer "F.Fab")
		)
		(fp_line
			(start 0.120396 0.3048)
			(end 0.120396 0.2794)
			(stroke
				(width 0.1)
				(type default)
			)
			(layer "F.Fab")
		)
		(fp_line
			(start 0.120396 0.2794)
			(end -0.12065 0.2794)
			(stroke
				(width 0.1)
				(type default)
			)
			(layer "F.Fab")
		)
		(fp_line
			(start -0.12065 0.3048)
			(end -0.67945 0.3048)
			(stroke
				(width 0.1)
				(type default)
			)
			(layer "F.Fab")
		)
		(fp_line
			(start -0.12065 0.2794)
			(end -0.12065 0.3048)
			(stroke
				(width 0.1)
				(type default)
			)
			(layer "F.Fab")
		)
		(fp_line
			(start -0.12065 -0.2794)
			(end 0.12065 -0.2794)
			(stroke
				(width 0.1)
				(type default)
			)
			(layer "F.Fab")
		)
		(fp_line
			(start -0.12065 -0.305054)
			(end -0.12065 -0.2794)
			(stroke
				(width 0.1)
				(type default)
			)
			(layer "F.Fab")
		)
		(fp_line
			(start -0.67945 0.3048)
			(end -0.67945 -0.305054)
			(stroke
				(width 0.1)
				(type default)
			)
			(layer "F.Fab")
		)
		(fp_line
			(start -0.67945 -0.305054)
			(end -0.12065 -0.305054)
			(stroke
				(width 0.1)
				(type default)
			)
			(layer "F.Fab")
		)
		(pad "1" smd circle
			(at -0.40005 0 180)
			(size 0 0)
			(layers "F.Cu" "F.Mask" "F.Paste")
			(net "P12V_SSD4_PG_G1")
		)
		(pad "2" smd circle
			(at 0.40005 0 180)
			(size 0 0)
			(layers "F.Cu" "F.Mask" "F.Paste")
			(net "GND")
		)
	)
	(footprint ""
		(layer "F.Cu")
		(at 20.274026 -72.766682 90)
		(property "Reference" "PR6904"
			(at 0 0 90)
			(layer "F.SilkS")
			(hide yes)
			(effects
				(font
					(size 1.27 1.27)
				)
			)
		)
		(property "Value" ""
			(at 0 0 90)
			(layer "F.Fab")
			(effects
				(font
					(size 1.27 1.27)
				)
			)
		)
		(duplicate_pad_numbers_are_jumpers no)
		(fp_line
			(start 0.7874 -0.4064)
			(end 0.7874 0.4064)
			(stroke
				(width 0.1524)
				(type default)
			)
			(layer "F.SilkS")
		)
		(fp_line
			(start -0.7874 -0.4064)
			(end 0.7874 -0.4064)
			(stroke
				(width 0.1524)
				(type default)
			)
			(layer "F.SilkS")
		)
		(fp_line
			(start 0.7874 0.4064)
			(end -0.7874 0.4064)
			(stroke
				(width 0.1524)
				(type default)
			)
			(layer "F.SilkS")
		)
		(fp_line
			(start -0.7874 0.4064)
			(end -0.7874 -0.4064)
			(stroke
				(width 0.1524)
				(type default)
			)
			(layer "F.SilkS")
		)
		(fp_line
			(start -0.12065 -0.305054)
			(end -0.12065 -0.2794)
			(stroke
				(width 0.1)
				(type default)
			)
			(layer "F.Fab")
		)
		(fp_line
			(start -0.67945 -0.305054)
			(end -0.12065 -0.305054)
			(stroke
				(width 0.1)
				(type default)
			)
			(layer "F.Fab")
		)
		(fp_line
			(start 0.67945 -0.3048)
			(end 0.67945 0.3048)
			(stroke
				(width 0.1)
				(type default)
			)
			(layer "F.Fab")
		)
		(fp_line
			(start 0.12065 -0.3048)
			(end 0.67945 -0.3048)
			(stroke
				(width 0.1)
				(type default)
			)
			(layer "F.Fab")
		)
		(fp_line
			(start 0.12065 -0.2794)
			(end 0.12065 -0.3048)
			(stroke
				(width 0.1)
				(type default)
			)
			(layer "F.Fab")
		)
		(fp_line
			(start -0.12065 -0.2794)
			(end 0.12065 -0.2794)
			(stroke
				(width 0.1)
				(type default)
			)
			(layer "F.Fab")
		)
		(fp_line
			(start 0.120396 0.2794)
			(end -0.12065 0.2794)
			(stroke
				(width 0.1)
				(type default)
			)
			(layer "F.Fab")
		)
		(fp_line
			(start -0.12065 0.2794)
			(end -0.12065 0.3048)
			(stroke
				(width 0.1)
				(type default)
			)
			(layer "F.Fab")
		)
		(fp_line
			(start 0.67945 0.3048)
			(end 0.120396 0.3048)
			(stroke
				(width 0.1)
				(type default)
			)
			(layer "F.Fab")
		)
		(fp_line
			(start 0.120396 0.3048)
			(end 0.120396 0.2794)
			(stroke
				(width 0.1)
				(type default)
			)
			(layer "F.Fab")
		)
		(fp_line
			(start -0.12065 0.3048)
			(end -0.67945 0.3048)
			(stroke
				(width 0.1)
				(type default)
			)
			(layer "F.Fab")
		)
		(fp_line
			(start -0.67945 0.3048)
			(end -0.67945 -0.305054)
			(stroke
				(width 0.1)
				(type default)
			)
			(layer "F.Fab")
		)
		(pad "1" smd circle
			(at -0.40005 0 90)
			(size 0 0)
			(layers "F.Cu" "F.Mask" "F.Paste")
			(net "P12V_SSD0_CO_MODE")
		)
		(pad "2" smd circle
			(at 0.40005 0 90)
			(size 0 0)
			(layers "F.Cu" "F.Mask" "F.Paste")
			(net "GND")
		)
	)
	(footprint ""
		(layer "F.Cu")
		(at 336.042 -161.798 180)
		(property "Reference" "R4808"
			(at 0 0 180)
			(layer "F.SilkS")
			(hide yes)
			(effects
				(font
					(size 1.27 1.27)
				)
			)
		)
		(property "Value" ""
			(at 0 0 180)
			(layer "F.Fab")
			(effects
				(font
					(size 1.27 1.27)
				)
			)
		)
		(duplicate_pad_numbers_are_jumpers no)
		(fp_line
			(start 0.7874 0.4064)
			(end -0.7874 0.4064)
			(stroke
				(width 0.1524)
				(type default)
			)
			(layer "F.SilkS")
		)
		(fp_line
			(start 0.7874 -0.4064)
			(end 0.7874 0.4064)
			(stroke
				(width 0.1524)
				(type default)
			)
			(layer "F.SilkS")
		)
		(fp_line
			(start -0.7874 0.4064)
			(end -0.7874 -0.4064)
			(stroke
				(width 0.1524)
				(type default)
			)
			(layer "F.SilkS")
		)
		(fp_line
			(start -0.7874 -0.4064)
			(end 0.7874 -0.4064)
			(stroke
				(width 0.1524)
				(type default)
			)
			(layer "F.SilkS")
		)
		(fp_line
			(start 0.67945 0.3048)
			(end 0.120396 0.3048)
			(stroke
				(width 0.1)
				(type default)
			)
			(layer "F.Fab")
		)
		(fp_line
			(start 0.67945 -0.3048)
			(end 0.67945 0.3048)
			(stroke
				(width 0.1)
				(type default)
			)
			(layer "F.Fab")
		)
		(fp_line
			(start 0.12065 -0.2794)
			(end 0.12065 -0.3048)
			(stroke
				(width 0.1)
				(type default)
			)
			(layer "F.Fab")
		)
		(fp_line
			(start 0.12065 -0.3048)
			(end 0.67945 -0.3048)
			(stroke
				(width 0.1)
				(type default)
			)
			(layer "F.Fab")
		)
		(fp_line
			(start 0.120396 0.3048)
			(end 0.120396 0.2794)
			(stroke
				(width 0.1)
				(type default)
			)
			(layer "F.Fab")
		)
		(fp_line
			(start 0.120396 0.2794)
			(end -0.12065 0.2794)
			(stroke
				(width 0.1)
				(type default)
			)
			(layer "F.Fab")
		)
		(fp_line
			(start -0.12065 0.3048)
			(end -0.67945 0.3048)
			(stroke
				(width 0.1)
				(type default)
			)
			(layer "F.Fab")
		)
		(fp_line
			(start -0.12065 0.2794)
			(end -0.12065 0.3048)
			(stroke
				(width 0.1)
				(type default)
			)
			(layer "F.Fab")
		)
		(fp_line
			(start -0.12065 -0.2794)
			(end 0.12065 -0.2794)
			(stroke
				(width 0.1)
				(type default)
			)
			(layer "F.Fab")
		)
		(fp_line
			(start -0.12065 -0.305054)
			(end -0.12065 -0.2794)
			(stroke
				(width 0.1)
				(type default)
			)
			(layer "F.Fab")
		)
		(fp_line
			(start -0.67945 0.3048)
			(end -0.67945 -0.305054)
			(stroke
				(width 0.1)
				(type default)
			)
			(layer "F.Fab")
		)
		(fp_line
			(start -0.67945 -0.305054)
			(end -0.12065 -0.305054)
			(stroke
				(width 0.1)
				(type default)
			)
			(layer "F.Fab")
		)
		(pad "1" smd circle
			(at -0.40005 0 180)
			(size 0 0)
			(layers "F.Cu" "F.Mask" "F.Paste")
			(net "PCA9555_0_PEX3_A1")
		)
		(pad "2" smd circle
			(at 0.40005 0 180)
			(size 0 0)
			(layers "F.Cu" "F.Mask" "F.Paste")
			(net "P3V3_AUX")
		)
	)
	(footprint ""
		(layer "F.Cu")
		(at 172.81525 -59.546236 90)
		(property "Reference" "C2890"
			(at 0 0 90)
			(layer "F.SilkS")
			(hide yes)
			(effects
				(font
					(size 1.27 1.27)
				)
			)
		)
		(property "Value" ""
			(at 0 0 90)
			(layer "F.Fab")
			(effects
				(font
					(size 1.27 1.27)
				)
			)
		)
		(duplicate_pad_numbers_are_jumpers no)
		(fp_line
			(start 0.7874 -0.4064)
			(end 0.7874 0.4064)
			(stroke
				(width 0.1524)
				(type default)
			)
			(layer "F.SilkS")
		)
		(fp_line
			(start -0.7874 -0.4064)
			(end 0.7874 -0.4064)
			(stroke
				(width 0.1524)
				(type default)
			)
			(layer "F.SilkS")
		)
		(fp_line
			(start 0.7874 0.4064)
			(end -0.7874 0.4064)
			(stroke
				(width 0.1524)
				(type default)
			)
			(layer "F.SilkS")
		)
		(fp_line
			(start -0.7874 0.4064)
			(end -0.7874 -0.4064)
			(stroke
				(width 0.1524)
				(type default)
			)
			(layer "F.SilkS")
		)
		(fp_line
			(start -0.12065 -0.305054)
			(end -0.12065 -0.2794)
			(stroke
				(width 0.1)
				(type default)
			)
			(layer "F.Fab")
		)
		(fp_line
			(start -0.67945 -0.305054)
			(end -0.12065 -0.305054)
			(stroke
				(width 0.1)
				(type default)
			)
			(layer "F.Fab")
		)
		(fp_line
			(start 0.67945 -0.3048)
			(end 0.67945 0.3048)
			(stroke
				(width 0.1)
				(type default)
			)
			(layer "F.Fab")
		)
		(fp_line
			(start 0.12065 -0.3048)
			(end 0.67945 -0.3048)
			(stroke
				(width 0.1)
				(type default)
			)
			(layer "F.Fab")
		)
		(fp_line
			(start 0.12065 -0.2794)
			(end 0.12065 -0.3048)
			(stroke
				(width 0.1)
				(type default)
			)
			(layer "F.Fab")
		)
		(fp_line
			(start -0.12065 -0.2794)
			(end 0.12065 -0.2794)
			(stroke
				(width 0.1)
				(type default)
			)
			(layer "F.Fab")
		)
		(fp_line
			(start 0.120396 0.2794)
			(end -0.12065 0.2794)
			(stroke
				(width 0.1)
				(type default)
			)
			(layer "F.Fab")
		)
		(fp_line
			(start -0.12065 0.2794)
			(end -0.12065 0.3048)
			(stroke
				(width 0.1)
				(type default)
			)
			(layer "F.Fab")
		)
		(fp_line
			(start 0.67945 0.3048)
			(end 0.120396 0.3048)
			(stroke
				(width 0.1)
				(type default)
			)
			(layer "F.Fab")
		)
		(fp_line
			(start 0.120396 0.3048)
			(end 0.120396 0.2794)
			(stroke
				(width 0.1)
				(type default)
			)
			(layer "F.Fab")
		)
		(fp_line
			(start -0.12065 0.3048)
			(end -0.67945 0.3048)
			(stroke
				(width 0.1)
				(type default)
			)
			(layer "F.Fab")
		)
		(fp_line
			(start -0.67945 0.3048)
			(end -0.67945 -0.305054)
			(stroke
				(width 0.1)
				(type default)
			)
			(layer "F.Fab")
		)
		(pad "1" smd circle
			(at -0.40005 0 90)
			(size 0 0)
			(layers "F.Cu" "F.Mask" "F.Paste")
			(net "SSD6_AUX_P3V3_EN_R")
		)
		(pad "2" smd circle
			(at 0.40005 0 90)
			(size 0 0)
			(layers "F.Cu" "F.Mask" "F.Paste")
			(net "GND")
		)
	)
)
